(kicad_pcb
	(version 20260206)
	(generator "pcbnew")
	(generator_version "10.0")
	(general
		(thickness 1.6)
		(legacy_teardrops no)
	)
	(paper "A4")
	(title_block
		(title "04192023_DAF0TMB3IC0_F0TG_MB_C_brd_V02_OCP.brd")
		(comment 1 "Grand Teton / footprints 7703-7710 of 8354")
	)
	(layers
		(0 "F.Cu" signal "TOP")
		(4 "In1.Cu" signal "GND")
		(6 "In2.Cu" signal "IN1")
		(8 "In3.Cu" signal "GND1")
		(10 "In4.Cu" signal "IN2")
		(12 "In5.Cu" signal "GND2")
		(14 "In6.Cu" signal "IN3")
		(16 "In7.Cu" signal "GND3")
		(18 "In8.Cu" signal "VCC")
		(20 "In9.Cu" signal "VCC1")
		(22 "In10.Cu" signal "GND4")
		(24 "In11.Cu" signal "IN4")
		(26 "In12.Cu" signal "GND5")
		(28 "In13.Cu" signal "IN5")
		(30 "In14.Cu" signal "GND6")
		(32 "In15.Cu" signal "IN6")
		(34 "In16.Cu" signal "GND7")
		(2 "B.Cu" signal "BOTTOM")
		(9 "F.Adhes" user "F.Adhesive")
		(11 "B.Adhes" user "B.Adhesive")
		(13 "F.Paste" user "Package Geometry/Pastemask Top")
		(15 "B.Paste" user "Package Geometry/Pastemask Bottom")
		(5 "F.SilkS" user "Ref Des/Silkscreen Top")
		(7 "B.SilkS" user "Ref Des/Silkscreen Bottom")
		(1 "F.Mask" user "Board Geometry/Soldermask Top")
		(3 "B.Mask" user "Board Geometry/Soldermask Bottom")
		(17 "Dwgs.User" user "User.Drawings")
		(19 "Cmts.User" user "User.Comments")
		(21 "Eco1.User" user "User.Eco1")
		(23 "Eco2.User" user "User.Eco2")
		(25 "Edge.Cuts" user "Board Geometry/Outline")
		(27 "Margin" user)
		(31 "F.CrtYd" user "Package Geometry/Place Bound Top")
		(29 "B.CrtYd" user "Package Geometry/Place Bound Bottom")
		(35 "F.Fab" user "Ref Des/Assembly Top")
		(33 "B.Fab" user "Ref Des/Assembly Bottom")
	)
	(footprint ""
		(layer "B.Cu")
		(at 318.306958 -203.917296 -90)
		(property "Reference" "R390"
			(at 0 0 90)
			(layer "B.SilkS")
			(hide yes)
			(effects
				(font
					(size 1.27 1.27)
				)
				(justify mirror)
			)
		)
		(property "Value" ""
			(at 0 0 90)
			(layer "B.Fab")
			(effects
				(font
					(size 1.27 1.27)
				)
				(justify mirror)
			)
		)
		(duplicate_pad_numbers_are_jumpers no)
		(fp_line
			(start -0.7874 0.4064)
			(end 0.7874 0.4064)
			(stroke
				(width 0.1524)
				(type default)
			)
			(layer "B.SilkS")
		)
		(fp_line
			(start 0.7874 0.4064)
			(end 0.7874 -0.4064)
			(stroke
				(width 0.1524)
				(type default)
			)
			(layer "B.SilkS")
		)
		(fp_line
			(start -0.7874 -0.4064)
			(end -0.7874 0.4064)
			(stroke
				(width 0.1524)
				(type default)
			)
			(layer "B.SilkS")
		)
		(fp_line
			(start 0.7874 -0.4064)
			(end -0.7874 -0.4064)
			(stroke
				(width 0.1524)
				(type default)
			)
			(layer "B.SilkS")
		)
		(fp_line
			(start -0.67945 0.3048)
			(end -0.120396 0.3048)
			(stroke
				(width 0.1)
				(type default)
			)
			(layer "B.Fab")
		)
		(fp_line
			(start -0.120396 0.3048)
			(end -0.120396 0.2794)
			(stroke
				(width 0.1)
				(type default)
			)
			(layer "B.Fab")
		)
		(fp_line
			(start 0.12065 0.3048)
			(end 0.67945 0.3048)
			(stroke
				(width 0.1)
				(type default)
			)
			(layer "B.Fab")
		)
		(fp_line
			(start 0.67945 0.3048)
			(end 0.67945 -0.305054)
			(stroke
				(width 0.1)
				(type default)
			)
			(layer "B.Fab")
		)
		(fp_line
			(start -0.120396 0.2794)
			(end 0.12065 0.2794)
			(stroke
				(width 0.1)
				(type default)
			)
			(layer "B.Fab")
		)
		(fp_line
			(start 0.12065 0.2794)
			(end 0.12065 0.3048)
			(stroke
				(width 0.1)
				(type default)
			)
			(layer "B.Fab")
		)
		(fp_line
			(start -0.12065 -0.2794)
			(end -0.12065 -0.3048)
			(stroke
				(width 0.1)
				(type default)
			)
			(layer "B.Fab")
		)
		(fp_line
			(start 0.12065 -0.2794)
			(end -0.12065 -0.2794)
			(stroke
				(width 0.1)
				(type default)
			)
			(layer "B.Fab")
		)
		(fp_line
			(start -0.67945 -0.3048)
			(end -0.67945 0.3048)
			(stroke
				(width 0.1)
				(type default)
			)
			(layer "B.Fab")
		)
		(fp_line
			(start -0.12065 -0.3048)
			(end -0.67945 -0.3048)
			(stroke
				(width 0.1)
				(type default)
			)
			(layer "B.Fab")
		)
		(fp_line
			(start 0.12065 -0.305054)
			(end 0.12065 -0.2794)
			(stroke
				(width 0.1)
				(type default)
			)
			(layer "B.Fab")
		)
		(fp_line
			(start 0.67945 -0.305054)
			(end 0.12065 -0.305054)
			(stroke
				(width 0.1)
				(type default)
			)
			(layer "B.Fab")
		)
		(pad "1" smd circle
			(at 0.40005 0 90)
			(size 0 0)
			(layers "B.Cu" "B.Mask" "B.Paste")
			(net "P3V3_AUX")
		)
		(pad "2" smd circle
			(at -0.40005 0 90)
			(size 0 0)
			(layers "B.Cu" "B.Mask" "B.Paste")
			(net "CPU0_CORETYPE0")
		)
	)
	(footprint ""
		(layer "B.Cu")
		(at 449.5546 -10.594086 90)
		(property "Reference" "R8423"
			(at 0 0 90)
			(layer "B.SilkS")
			(hide yes)
			(effects
				(font
					(size 1.27 1.27)
				)
				(justify mirror)
			)
		)
		(property "Value" ""
			(at 0 0 90)
			(layer "B.Fab")
			(effects
				(font
					(size 1.27 1.27)
				)
				(justify mirror)
			)
		)
		(duplicate_pad_numbers_are_jumpers no)
		(fp_line
			(start 0.7874 -0.4064)
			(end -0.7874 -0.4064)
			(stroke
				(width 0.1524)
				(type default)
			)
			(layer "B.SilkS")
		)
		(fp_line
			(start -0.7874 -0.4064)
			(end -0.7874 0.4064)
			(stroke
				(width 0.1524)
				(type default)
			)
			(layer "B.SilkS")
		)
		(fp_line
			(start 0.7874 0.4064)
			(end 0.7874 -0.4064)
			(stroke
				(width 0.1524)
				(type default)
			)
			(layer "B.SilkS")
		)
		(fp_line
			(start -0.7874 0.4064)
			(end 0.7874 0.4064)
			(stroke
				(width 0.1524)
				(type default)
			)
			(layer "B.SilkS")
		)
		(fp_line
			(start 0.67945 -0.305054)
			(end 0.12065 -0.305054)
			(stroke
				(width 0.1)
				(type default)
			)
			(layer "B.Fab")
		)
		(fp_line
			(start 0.12065 -0.305054)
			(end 0.12065 -0.2794)
			(stroke
				(width 0.1)
				(type default)
			)
			(layer "B.Fab")
		)
		(fp_line
			(start -0.12065 -0.3048)
			(end -0.67945 -0.3048)
			(stroke
				(width 0.1)
				(type default)
			)
			(layer "B.Fab")
		)
		(fp_line
			(start -0.67945 -0.3048)
			(end -0.67945 0.3048)
			(stroke
				(width 0.1)
				(type default)
			)
			(layer "B.Fab")
		)
		(fp_line
			(start 0.12065 -0.2794)
			(end -0.12065 -0.2794)
			(stroke
				(width 0.1)
				(type default)
			)
			(layer "B.Fab")
		)
		(fp_line
			(start -0.12065 -0.2794)
			(end -0.12065 -0.3048)
			(stroke
				(width 0.1)
				(type default)
			)
			(layer "B.Fab")
		)
		(fp_line
			(start 0.12065 0.2794)
			(end 0.12065 0.3048)
			(stroke
				(width 0.1)
				(type default)
			)
			(layer "B.Fab")
		)
		(fp_line
			(start -0.120396 0.2794)
			(end 0.12065 0.2794)
			(stroke
				(width 0.1)
				(type default)
			)
			(layer "B.Fab")
		)
		(fp_line
			(start 0.67945 0.3048)
			(end 0.67945 -0.305054)
			(stroke
				(width 0.1)
				(type default)
			)
			(layer "B.Fab")
		)
		(fp_line
			(start 0.12065 0.3048)
			(end 0.67945 0.3048)
			(stroke
				(width 0.1)
				(type default)
			)
			(layer "B.Fab")
		)
		(fp_line
			(start -0.120396 0.3048)
			(end -0.120396 0.2794)
			(stroke
				(width 0.1)
				(type default)
			)
			(layer "B.Fab")
		)
		(fp_line
			(start -0.67945 0.3048)
			(end -0.120396 0.3048)
			(stroke
				(width 0.1)
				(type default)
			)
			(layer "B.Fab")
		)
		(pad "1" smd circle
			(at 0.40005 0 270)
			(size 0 0)
			(layers "B.Cu" "B.Mask" "B.Paste")
			(net "SGPIO_OCP_SFF_CLK")
		)
		(pad "2" smd circle
			(at -0.40005 0 270)
			(size 0 0)
			(layers "B.Cu" "B.Mask" "B.Paste")
			(net "P3V3_OCP_SFF")
		)
	)
	(footprint ""
		(layer "B.Cu")
		(at 197.94855 -194.8942 180)
		(property "Reference" "R1590"
			(at 0 0 0)
			(layer "B.SilkS")
			(hide yes)
			(effects
				(font
					(size 1.27 1.27)
				)
				(justify mirror)
			)
		)
		(property "Value" ""
			(at 0 0 0)
			(layer "B.Fab")
			(effects
				(font
					(size 1.27 1.27)
				)
				(justify mirror)
			)
		)
		(duplicate_pad_numbers_are_jumpers no)
		(fp_line
			(start 0.7874 0.4064)
			(end 0.7874 -0.4064)
			(stroke
				(width 0.1524)
				(type default)
			)
			(layer "B.SilkS")
		)
		(fp_line
			(start 0.7874 -0.4064)
			(end -0.7874 -0.4064)
			(stroke
				(width 0.1524)
				(type default)
			)
			(layer "B.SilkS")
		)
		(fp_line
			(start -0.7874 0.4064)
			(end 0.7874 0.4064)
			(stroke
				(width 0.1524)
				(type default)
			)
			(layer "B.SilkS")
		)
		(fp_line
			(start -0.7874 -0.4064)
			(end -0.7874 0.4064)
			(stroke
				(width 0.1524)
				(type default)
			)
			(layer "B.SilkS")
		)
		(fp_line
			(start 0.67945 0.3048)
			(end 0.67945 -0.305054)
			(stroke
				(width 0.1)
				(type default)
			)
			(layer "B.Fab")
		)
		(fp_line
			(start 0.67945 -0.305054)
			(end 0.12065 -0.305054)
			(stroke
				(width 0.1)
				(type default)
			)
			(layer "B.Fab")
		)
		(fp_line
			(start 0.12065 0.3048)
			(end 0.67945 0.3048)
			(stroke
				(width 0.1)
				(type default)
			)
			(layer "B.Fab")
		)
		(fp_line
			(start 0.12065 0.2794)
			(end 0.12065 0.3048)
			(stroke
				(width 0.1)
				(type default)
			)
			(layer "B.Fab")
		)
		(fp_line
			(start 0.12065 -0.2794)
			(end -0.12065 -0.2794)
			(stroke
				(width 0.1)
				(type default)
			)
			(layer "B.Fab")
		)
		(fp_line
			(start 0.12065 -0.305054)
			(end 0.12065 -0.2794)
			(stroke
				(width 0.1)
				(type default)
			)
			(layer "B.Fab")
		)
		(fp_line
			(start -0.120396 0.3048)
			(end -0.120396 0.2794)
			(stroke
				(width 0.1)
				(type default)
			)
			(layer "B.Fab")
		)
		(fp_line
			(start -0.120396 0.2794)
			(end 0.12065 0.2794)
			(stroke
				(width 0.1)
				(type default)
			)
			(layer "B.Fab")
		)
		(fp_line
			(start -0.12065 -0.2794)
			(end -0.12065 -0.3048)
			(stroke
				(width 0.1)
				(type default)
			)
			(layer "B.Fab")
		)
		(fp_line
			(start -0.12065 -0.3048)
			(end -0.67945 -0.3048)
			(stroke
				(width 0.1)
				(type default)
			)
			(layer "B.Fab")
		)
		(fp_line
			(start -0.67945 0.3048)
			(end -0.120396 0.3048)
			(stroke
				(width 0.1)
				(type default)
			)
			(layer "B.Fab")
		)
		(fp_line
			(start -0.67945 -0.3048)
			(end -0.67945 0.3048)
			(stroke
				(width 0.1)
				(type default)
			)
			(layer "B.Fab")
		)
		(pad "1" smd circle
			(at 0.40005 0)
			(size 0 0)
			(layers "B.Cu" "B.Mask" "B.Paste")
			(net "I3C_SPD_DDRGL_CPU1_SCL")
		)
		(pad "2" smd circle
			(at -0.40005 0)
			(size 0 0)
			(layers "B.Cu" "B.Mask" "B.Paste")
			(net "I3C_SPD_DDRK_CPU1_SCL")
		)
	)
	(footprint ""
		(layer "B.Cu")
		(at 185.166 -359.537)
		(property "Reference" "PC8006"
			(at 0 0 0)
			(layer "B.SilkS")
			(hide yes)
			(effects
				(font
					(size 1.27 1.27)
				)
				(justify mirror)
			)
		)
		(property "Value" ""
			(at 0 0 0)
			(layer "B.Fab")
			(effects
				(font
					(size 1.27 1.27)
				)
				(justify mirror)
			)
		)
		(duplicate_pad_numbers_are_jumpers no)
		(fp_line
			(start -1.524 -0.762)
			(end -1.524 0.762)
			(stroke
				(width 0.1524)
				(type default)
			)
			(layer "B.SilkS")
		)
		(fp_line
			(start -1.524 0.762)
			(end 1.524 0.762)
			(stroke
				(width 0.1524)
				(type default)
			)
			(layer "B.SilkS")
		)
		(fp_line
			(start 1.524 -0.762)
			(end -1.524 -0.762)
			(stroke
				(width 0.1524)
				(type default)
			)
			(layer "B.SilkS")
		)
		(fp_line
			(start 1.524 0.762)
			(end 1.524 -0.762)
			(stroke
				(width 0.1524)
				(type default)
			)
			(layer "B.SilkS")
		)
		(fp_line
			(start -1.1049 -0.724916)
			(end 1.1049 -0.724916)
			(stroke
				(width 0.1)
				(type default)
			)
			(layer "B.Fab")
		)
		(fp_line
			(start -1.1049 0.724916)
			(end -1.1049 -0.724916)
			(stroke
				(width 0.1)
				(type default)
			)
			(layer "B.Fab")
		)
		(fp_line
			(start 1.1049 -0.724916)
			(end 1.1049 0.724916)
			(stroke
				(width 0.1)
				(type default)
			)
			(layer "B.Fab")
		)
		(fp_line
			(start 1.1049 0.724916)
			(end -1.1049 0.724916)
			(stroke
				(width 0.1)
				(type default)
			)
			(layer "B.Fab")
		)
		(pad "1" smd rect
			(at 0.889 0)
			(size 1.016 1.27)
			(layers "B.Cu" "B.Mask" "B.Paste")
			(net "SW_P12V_AUX_PVDD11_S3_P1_FLT")
		)
		(pad "2" smd rect
			(at -0.889 0)
			(size 1.016 1.27)
			(layers "B.Cu" "B.Mask" "B.Paste")
			(net "GND")
		)
	)
	(footprint ""
		(layer "B.Cu")
		(at 365.09579 -392.1252 180)
		(property "Reference" "R1105"
			(at 0 0 0)
			(layer "B.SilkS")
			(hide yes)
			(effects
				(font
					(size 1.27 1.27)
				)
				(justify mirror)
			)
		)
		(property "Value" ""
			(at 0 0 0)
			(layer "B.Fab")
			(effects
				(font
					(size 1.27 1.27)
				)
				(justify mirror)
			)
		)
		(duplicate_pad_numbers_are_jumpers no)
		(fp_line
			(start 0.32512 0.175006)
			(end 0.32512 -0.175006)
			(stroke
				(width 0.1)
				(type default)
			)
			(layer "B.Fab")
		)
		(fp_line
			(start 0.32512 -0.175006)
			(end -0.32512 -0.175006)
			(stroke
				(width 0.1)
				(type default)
			)
			(layer "B.Fab")
		)
		(fp_line
			(start -0.32512 0.175006)
			(end 0.32512 0.175006)
			(stroke
				(width 0.1)
				(type default)
			)
			(layer "B.Fab")
		)
		(fp_line
			(start -0.32512 -0.175006)
			(end -0.32512 0.175006)
			(stroke
				(width 0.1)
				(type default)
			)
			(layer "B.Fab")
		)
		(pad "1" smd rect
			(at 0.2667 0)
			(size 0.3048 0.381)
			(layers "B.Cu" "B.Mask" "B.Paste")
			(net "P1V8_CPU0_RT_1D")
		)
		(pad "2" smd rect
			(at -0.2667 0 180)
			(size 0.3048 0.381)
			(layers "B.Cu" "B.Mask" "B.Paste")
			(net "RT_CPU0_P3_SCAN_MODE")
		)
	)
	(footprint ""
		(layer "B.Cu")
		(at 187.815728 -193.996564)
		(property "Reference" "R113"
			(at 0 0 0)
			(layer "B.SilkS")
			(hide yes)
			(effects
				(font
					(size 1.27 1.27)
				)
				(justify mirror)
			)
		)
		(property "Value" ""
			(at 0 0 0)
			(layer "B.Fab")
			(effects
				(font
					(size 1.27 1.27)
				)
				(justify mirror)
			)
		)
		(duplicate_pad_numbers_are_jumpers no)
		(fp_line
			(start -0.7874 -0.4064)
			(end -0.7874 0.4064)
			(stroke
				(width 0.1524)
				(type default)
			)
			(layer "B.SilkS")
		)
		(fp_line
			(start -0.7874 0.4064)
			(end 0.7874 0.4064)
			(stroke
				(width 0.1524)
				(type default)
			)
			(layer "B.SilkS")
		)
		(fp_line
			(start 0.7874 -0.4064)
			(end -0.7874 -0.4064)
			(stroke
				(width 0.1524)
				(type default)
			)
			(layer "B.SilkS")
		)
		(fp_line
			(start 0.7874 0.4064)
			(end 0.7874 -0.4064)
			(stroke
				(width 0.1524)
				(type default)
			)
			(layer "B.SilkS")
		)
		(fp_line
			(start -0.67945 -0.3048)
			(end -0.67945 0.3048)
			(stroke
				(width 0.1)
				(type default)
			)
			(layer "B.Fab")
		)
		(fp_line
			(start -0.67945 0.3048)
			(end -0.120396 0.3048)
			(stroke
				(width 0.1)
				(type default)
			)
			(layer "B.Fab")
		)
		(fp_line
			(start -0.12065 -0.3048)
			(end -0.67945 -0.3048)
			(stroke
				(width 0.1)
				(type default)
			)
			(layer "B.Fab")
		)
		(fp_line
			(start -0.12065 -0.2794)
			(end -0.12065 -0.3048)
			(stroke
				(width 0.1)
				(type default)
			)
			(layer "B.Fab")
		)
		(fp_line
			(start -0.120396 0.2794)
			(end 0.12065 0.2794)
			(stroke
				(width 0.1)
				(type default)
			)
			(layer "B.Fab")
		)
		(fp_line
			(start -0.120396 0.3048)
			(end -0.120396 0.2794)
			(stroke
				(width 0.1)
				(type default)
			)
			(layer "B.Fab")
		)
		(fp_line
			(start 0.12065 -0.305054)
			(end 0.12065 -0.2794)
			(stroke
				(width 0.1)
				(type default)
			)
			(layer "B.Fab")
		)
		(fp_line
			(start 0.12065 -0.2794)
			(end -0.12065 -0.2794)
			(stroke
				(width 0.1)
				(type default)
			)
			(layer "B.Fab")
		)
		(fp_line
			(start 0.12065 0.2794)
			(end 0.12065 0.3048)
			(stroke
				(width 0.1)
				(type default)
			)
			(layer "B.Fab")
		)
		(fp_line
			(start 0.12065 0.3048)
			(end 0.67945 0.3048)
			(stroke
				(width 0.1)
				(type default)
			)
			(layer "B.Fab")
		)
		(fp_line
			(start 0.67945 -0.305054)
			(end 0.12065 -0.305054)
			(stroke
				(width 0.1)
				(type default)
			)
			(layer "B.Fab")
		)
		(fp_line
			(start 0.67945 0.3048)
			(end 0.67945 -0.305054)
			(stroke
				(width 0.1)
				(type default)
			)
			(layer "B.Fab")
		)
		(pad "1" smd circle
			(at 0.40005 0 180)
			(size 0 0)
			(layers "B.Cu" "B.Mask" "B.Paste")
			(net "P3V3")
		)
		(pad "2" smd circle
			(at -0.40005 0 180)
			(size 0 0)
			(layers "B.Cu" "B.Mask" "B.Paste")
			(net "PWRGD_CHJ_CPU1_DIMM")
		)
	)
	(footprint ""
		(layer "B.Cu")
		(at 388.478522 -395.148562 90)
		(property "Reference" "C1019"
			(at 0 0 90)
			(layer "B.SilkS")
			(hide yes)
			(effects
				(font
					(size 1.27 1.27)
				)
				(justify mirror)
			)
		)
		(property "Value" ""
			(at 0 0 90)
			(layer "B.Fab")
			(effects
				(font
					(size 1.27 1.27)
				)
				(justify mirror)
			)
		)
		(duplicate_pad_numbers_are_jumpers no)
		(fp_line
			(start 0.299974 -0.150114)
			(end -0.299974 -0.150114)
			(stroke
				(width 0.1)
				(type default)
			)
			(layer "B.Fab")
		)
		(fp_line
			(start -0.299974 -0.150114)
			(end -0.299974 0.150114)
			(stroke
				(width 0.1)
				(type default)
			)
			(layer "B.Fab")
		)
		(fp_line
			(start 0.299974 0.150114)
			(end 0.299974 -0.150114)
			(stroke
				(width 0.1)
				(type default)
			)
			(layer "B.Fab")
		)
		(fp_line
			(start -0.299974 0.150114)
			(end 0.299974 0.150114)
			(stroke
				(width 0.1)
				(type default)
			)
			(layer "B.Fab")
		)
		(pad "1" smd rect
			(at 0.2667 0 270)
			(size 0.3048 0.381)
			(layers "B.Cu" "B.Mask" "B.Paste")
			(net "P0V9_CPU0_RT3_2A")
		)
		(pad "2" smd rect
			(at -0.2667 0 270)
			(size 0.3048 0.381)
			(layers "B.Cu" "B.Mask" "B.Paste")
			(net "GND")
		)
	)
	(footprint ""
		(layer "B.Cu")
		(at 254.635 -338.51596 180)
		(property "Reference" "R1374"
			(at 0 0 0)
			(layer "B.SilkS")
			(hide yes)
			(effects
				(font
					(size 1.27 1.27)
				)
				(justify mirror)
			)
		)
		(property "Value" ""
			(at 0 0 0)
			(layer "B.Fab")
			(effects
				(font
					(size 1.27 1.27)
				)
				(justify mirror)
			)
		)
		(duplicate_pad_numbers_are_jumpers no)
		(fp_line
			(start 0.32512 0.175006)
			(end 0.32512 -0.175006)
			(stroke
				(width 0.1)
				(type default)
			)
			(layer "B.Fab")
		)
		(fp_line
			(start 0.32512 -0.175006)
			(end -0.32512 -0.175006)
			(stroke
				(width 0.1)
				(type default)
			)
			(layer "B.Fab")
		)
		(fp_line
			(start -0.32512 0.175006)
			(end 0.32512 0.175006)
			(stroke
				(width 0.1)
				(type default)
			)
			(layer "B.Fab")
		)
		(fp_line
			(start -0.32512 -0.175006)
			(end -0.32512 0.175006)
			(stroke
				(width 0.1)
				(type default)
			)
			(layer "B.Fab")
		)
		(pad "1" smd rect
			(at 0.2667 0)
			(size 0.3048 0.381)
			(layers "B.Cu" "B.Mask" "B.Paste")
			(net "P1V8_CPU0_RT_1D")
		)
		(pad "2" smd rect
			(at -0.2667 0 180)
			(size 0.3048 0.381)
			(layers "B.Cu" "B.Mask" "B.Paste")
			(net "SMB_RT_CPU0_P1_ROM_MUX_2D_R_SCL")
		)
	)
)
